# BASEBOARD_FAB2 (Tioga Pass) — schematic netlist excerpt (pin names and nets, part order shuffled) for the footprints in the layout excerpt that follows; sources: Cadence DE-HDL packaged netlist, KiCad conversion of Wiwynn_Tioga_Pass_MB.brd

RF4  RES  1.0K 0.1% CHIP  pkg 0402  page 201 : A = VR_PVCCIN_CPU0_AIREF4 ; B = ISENSE_PVCCIN_CPU0_PH4_IMON
R8G13  RES  0.0 5% CHIP  pkg 0402  page 189 : A = JTAG_PLD_TMS ; B = JTAG_PLD_TMS_MUX
C5D57  CAP_A  22.0UF 4V 20% X6S  pkg 0603V  page 217 : A = PVDDQ_ABC ; B = GND

(kicad_pcb
	(version 20260206)
	(generator "pcbnew")
	(generator_version "10.0")
	(general
		(thickness 1.6)
		(legacy_teardrops no)
	)
	(paper "A4")
	(title_block
		(title "Wiwynn_Tioga_Pass_MB.brd")
		(comment 1 "Tioga Pass / footprints 1677-1679 of 4770")
	)
	(layers
		(0 "F.Cu" signal "TOP")
		(4 "In1.Cu" signal "L2GND")
		(6 "In2.Cu" signal "L3")
		(8 "In3.Cu" signal "L4GND")
		(10 "In4.Cu" signal "L5")
		(12 "In5.Cu" signal "L6GND")
		(14 "In6.Cu" signal "L7VCC")
		(16 "In7.Cu" signal "L8VCC")
		(18 "In8.Cu" signal "L9GND")
		(20 "In9.Cu" signal "L10")
		(22 "In10.Cu" signal "L11GND")
		(24 "In11.Cu" signal "L12")
		(26 "In12.Cu" signal "L13GND")
		(2 "B.Cu" signal "BOTTOM")
		(9 "F.Adhes" user "F.Adhesive")
		(11 "B.Adhes" user "B.Adhesive")
		(13 "F.Paste" user "Package Geometry/Pastemask Top")
		(15 "B.Paste" user "Package Geometry/Pastemask Bottom")
		(5 "F.SilkS" user "Ref Des/Silkscreen Top")
		(7 "B.SilkS" user "Ref Des/Silkscreen Bottom")
		(1 "F.Mask" user "Board Geometry/Soldermask Top")
		(3 "B.Mask" user "Board Geometry/Soldermask Bottom")
		(17 "Dwgs.User" user "User.Drawings")
		(19 "Cmts.User" user "User.Comments")
		(21 "Eco1.User" user "User.Eco1")
		(23 "Eco2.User" user "User.Eco2")
		(25 "Edge.Cuts" user "Board Geometry/Outline")
		(27 "Margin" user)
		(31 "F.CrtYd" user "Package Geometry/Place Bound Top")
		(29 "B.CrtYd" user "Package Geometry/Place Bound Bottom")
		(35 "F.Fab" user "Ref Des/Assembly Top")
		(33 "B.Fab" user "Ref Des/Assembly Bottom")
	)
	(footprint ""
		(layer "F.Cu")
		(at 267.146024 -68.412614 180)
		(property "Reference" "C5D57"
			(at 0 0 180)
			(layer "F.SilkS")
			(hide yes)
			(effects
				(font
					(size 1.27 1.27)
				)
			)
		)
		(property "Value" ""
			(at 0 0 180)
			(layer "F.Fab")
			(effects
				(font
					(size 1.27 1.27)
				)
			)
		)
		(duplicate_pad_numbers_are_jumpers no)
		(fp_poly
			(pts
				(xy -0.4953 -0.2032) (xy 0.4953 -0.2032) (xy 0.4953 1.6002) (xy -0.4953 1.6002)
			)
			(stroke
				(width 0)
				(type default)
			)
			(fill no)
			(layer "F.CrtYd")
		)
		(fp_line
			(start 0.4953 1.6002)
			(end -0.4953 1.6002)
			(stroke
				(width 0.1)
				(type default)
			)
			(layer "F.Fab")
		)
		(fp_line
			(start 0.4953 -0.2032)
			(end 0.4953 1.6002)
			(stroke
				(width 0.1)
				(type default)
			)
			(layer "F.Fab")
		)
		(fp_line
			(start -0.4953 1.6002)
			(end -0.4953 -0.2032)
			(stroke
				(width 0.1)
				(type default)
			)
			(layer "F.Fab")
		)
		(fp_line
			(start -0.4953 -0.2032)
			(end 0.4953 -0.2032)
			(stroke
				(width 0.1)
				(type default)
			)
			(layer "F.Fab")
		)
		(pad "1" smd rect
			(at 0 0 180)
			(size 0.762 0.889)
			(layers "F.Cu" "F.Mask" "F.Paste")
			(net "PVDDQ_ABC")
		)
		(pad "2" smd rect
			(at 0 1.397 180)
			(size 0.762 0.889)
			(layers "F.Cu" "F.Mask" "F.Paste")
			(net "GND")
		)
		(zone
			(layer "F.Cu")
			(hatch none 0.5)
			(connect_pads
				(clearance 0)
			)
			(min_thickness 0.25)
			(keepout
				(tracks not_allowed)
				(vias allowed)
				(pads allowed)
				(copperpour not_allowed)
				(footprints allowed)
			)
			(placement
				(enabled no)
				(sheetname "")
			)
			(fill
				(thermal_gap 0.5)
				(thermal_bridge_width 0.5)
				(island_removal_mode 0)
			)
			(polygon
				(pts
					(xy 267.527024 -68.857114) (xy 266.765024 -68.857114) (xy 266.765024 -69.365114) (xy 267.527024 -69.365114)
				)
			)
		)
	)
	(footprint ""
		(layer "F.Cu")
		(at 190.1698 -69.3039 180)
		(property "Reference" "RF4"
			(at -0.8382 -0.67818 180)
			(unlocked yes)
			(layer "F.SilkS")
			(effects
				(font
					(size 0.4064 0.254)
					(thickness 0.1524)
				)
				(justify left)
			)
		)
		(property "Value" ""
			(at 0 0 180)
			(layer "F.Fab")
			(effects
				(font
					(size 1.27 1.27)
				)
			)
		)
		(duplicate_pad_numbers_are_jumpers no)
		(fp_poly
			(pts
				(xy -0.2794 -0.1016) (xy 0.2794 -0.1016) (xy 0.2794 0.9906) (xy -0.2794 0.9906)
			)
			(stroke
				(width 0)
				(type default)
			)
			(fill no)
			(layer "F.CrtYd")
		)
		(fp_line
			(start 0.2794 0.9906)
			(end 0.2794 -0.1016)
			(stroke
				(width 0.1)
				(type default)
			)
			(layer "F.Fab")
		)
		(fp_line
			(start 0.2794 -0.1016)
			(end -0.2794 -0.1016)
			(stroke
				(width 0.1)
				(type default)
			)
			(layer "F.Fab")
		)
		(fp_line
			(start -0.2794 0.9906)
			(end 0.2794 0.9906)
			(stroke
				(width 0.1)
				(type default)
			)
			(layer "F.Fab")
		)
		(fp_line
			(start -0.2794 -0.1016)
			(end -0.2794 0.9906)
			(stroke
				(width 0.1)
				(type default)
			)
			(layer "F.Fab")
		)
		(pad "1" smd rect
			(at 0 0 180)
			(size 0.508 0.508)
			(layers "F.Cu" "F.Mask" "F.Paste")
			(net "VR_PVCCIN_CPU0_AIREF4")
		)
		(pad "2" smd rect
			(at 0 0.889 180)
			(size 0.508 0.508)
			(layers "F.Cu" "F.Mask" "F.Paste")
			(net "ISENSE_PVCCIN_CPU0_PH4_IMON")
		)
		(zone
			(layer "F.Cu")
			(hatch none 0.5)
			(connect_pads
				(clearance 0)
			)
			(min_thickness 0.25)
			(keepout
				(tracks not_allowed)
				(vias allowed)
				(pads allowed)
				(copperpour not_allowed)
				(footprints allowed)
			)
			(placement
				(enabled no)
				(sheetname "")
			)
			(fill
				(thermal_gap 0.5)
				(thermal_bridge_width 0.5)
				(island_removal_mode 0)
			)
			(polygon
				(pts
					(xy 190.4238 -69.9389) (xy 189.9158 -69.9389) (xy 189.9158 -69.5579) (xy 190.4238 -69.5579)
				)
			)
		)
		(zone
			(layer "F.Cu")
			(hatch none 0.5)
			(connect_pads
				(clearance 0)
			)
			(min_thickness 0.25)
			(keepout
				(tracks allowed)
				(vias not_allowed)
				(pads allowed)
				(copperpour not_allowed)
				(footprints allowed)
			)
			(placement
				(enabled no)
				(sheetname "")
			)
			(fill
				(thermal_gap 0.5)
				(thermal_bridge_width 0.5)
				(island_removal_mode 0)
			)
			(polygon
				(pts
					(xy 190.4238 -69.5579) (xy 189.9158 -69.5579) (xy 189.9158 -69.9389) (xy 190.4238 -69.9389)
				)
			)
		)
	)
	(footprint ""
		(layer "F.Cu")
		(at 403.606 3.2004 90)
		(property "Reference" "R8G13"
			(at 0 0 90)
			(layer "F.SilkS")
			(hide yes)
			(effects
				(font
					(size 1.27 1.27)
				)
			)
		)
		(property "Value" ""
			(at 0 0 90)
			(layer "F.Fab")
			(effects
				(font
					(size 1.27 1.27)
				)
			)
		)
		(duplicate_pad_numbers_are_jumpers no)
		(fp_poly
			(pts
				(xy -0.2794 -0.1016) (xy 0.2794 -0.1016) (xy 0.2794 0.9906) (xy -0.2794 0.9906)
			)
			(stroke
				(width 0)
				(type default)
			)
			(fill no)
			(layer "F.CrtYd")
		)
		(fp_line
			(start 0.2794 -0.1016)
			(end -0.2794 -0.1016)
			(stroke
				(width 0.1)
				(type default)
			)
			(layer "F.Fab")
		)
		(fp_line
			(start -0.2794 -0.1016)
			(end -0.2794 0.9906)
			(stroke
				(width 0.1)
				(type default)
			)
			(layer "F.Fab")
		)
		(fp_line
			(start 0.2794 0.9906)
			(end 0.2794 -0.1016)
			(stroke
				(width 0.1)
				(type default)
			)
			(layer "F.Fab")
		)
		(fp_line
			(start -0.2794 0.9906)
			(end 0.2794 0.9906)
			(stroke
				(width 0.1)
				(type default)
			)
			(layer "F.Fab")
		)
		(pad "1" smd rect
			(at 0 0 90)
			(size 0.508 0.508)
			(layers "F.Cu" "F.Mask" "F.Paste")
			(net "JTAG_PLD_TMS")
		)
		(pad "2" smd rect
			(at 0 0.889 90)
			(size 0.508 0.508)
			(layers "F.Cu" "F.Mask" "F.Paste")
			(net "JTAG_PLD_TMS_MUX")
		)
		(zone
			(layer "F.Cu")
			(hatch none 0.5)
			(connect_pads
				(clearance 0)
			)
			(min_thickness 0.25)
			(keepout
				(tracks allowed)
				(vias not_allowed)
				(pads allowed)
				(copperpour not_allowed)
				(footprints allowed)
			)
			(placement
				(enabled no)
				(sheetname "")
			)
			(fill
				(thermal_gap 0.5)
				(thermal_bridge_width 0.5)
				(island_removal_mode 0)
			)
			(polygon
				(pts
					(xy 403.86 3.4544) (xy 403.86 2.9464) (xy 404.241 2.9464) (xy 404.241 3.4544)
				)
			)
		)
		(zone
			(layer "F.Cu")
			(hatch none 0.5)
			(connect_pads
				(clearance 0)
			)
			(min_thickness 0.25)
			(keepout
				(tracks not_allowed)
				(vias allowed)
				(pads allowed)
				(copperpour not_allowed)
				(footprints allowed)
			)
			(placement
				(enabled no)
				(sheetname "")
			)
			(fill
				(thermal_gap 0.5)
				(thermal_bridge_width 0.5)
				(island_removal_mode 0)
			)
			(polygon
				(pts
					(xy 404.241 3.4544) (xy 404.241 2.9464) (xy 403.86 2.9464) (xy 403.86 3.4544)
				)
			)
		)
	)
)
